# T6G (Grand Teton) — schematic netlist excerpt (pin names and nets, part order shuffled) for the footprints in the layout excerpt that follows; sources: Cadence DE-HDL packaged netlist, KiCad conversion of 04192023_DAF0TMB3IC0_F0TG_MB_C_brd_V02_OCP.brd

Q62  MOSFET_N  BSS138K IC  pkg SMLF  page 172
  DRAIN  = JTAG_BMC_OE_N
  GATE  = JTAG_BMC_OE
  SOURCE  = GND

PC287  Q_CAP  2.2UF 10V 10% X6S  pkg C0402  page 212 : A = PVDDCR_CPU0_P1_VCC4 ; B = GND
C726  Q_CAP_DIFFBUS  DIFF BUS_0.22UF 6.3V 20% X6S  pkg C0201  page 66 : \1\ = P5E_CPU1_P1_TX_C_DN<7> ; \2\ = P5E_CPU1_P1_TX_DN<7>

(kicad_pcb
	(version 20260206)
	(generator "pcbnew")
	(generator_version "10.0")
	(general
		(thickness 1.6)
		(legacy_teardrops no)
	)
	(paper "A4")
	(title_block
		(title "04192023_DAF0TMB3IC0_F0TG_MB_C_brd_V02_OCP.brd")
		(comment 1 "Grand Teton / footprints 1570-1572 of 8354")
	)
	(layers
		(0 "F.Cu" signal "TOP")
		(4 "In1.Cu" signal "GND")
		(6 "In2.Cu" signal "IN1")
		(8 "In3.Cu" signal "GND1")
		(10 "In4.Cu" signal "IN2")
		(12 "In5.Cu" signal "GND2")
		(14 "In6.Cu" signal "IN3")
		(16 "In7.Cu" signal "GND3")
		(18 "In8.Cu" signal "VCC")
		(20 "In9.Cu" signal "VCC1")
		(22 "In10.Cu" signal "GND4")
		(24 "In11.Cu" signal "IN4")
		(26 "In12.Cu" signal "GND5")
		(28 "In13.Cu" signal "IN5")
		(30 "In14.Cu" signal "GND6")
		(32 "In15.Cu" signal "IN6")
		(34 "In16.Cu" signal "GND7")
		(2 "B.Cu" signal "BOTTOM")
		(9 "F.Adhes" user "F.Adhesive")
		(11 "B.Adhes" user "B.Adhesive")
		(13 "F.Paste" user "Package Geometry/Pastemask Top")
		(15 "B.Paste" user "Package Geometry/Pastemask Bottom")
		(5 "F.SilkS" user "Ref Des/Silkscreen Top")
		(7 "B.SilkS" user "Ref Des/Silkscreen Bottom")
		(1 "F.Mask" user "Board Geometry/Soldermask Top")
		(3 "B.Mask" user "Board Geometry/Soldermask Bottom")
		(17 "Dwgs.User" user "User.Drawings")
		(19 "Cmts.User" user "User.Comments")
		(21 "Eco1.User" user "User.Eco1")
		(23 "Eco2.User" user "User.Eco2")
		(25 "Edge.Cuts" user "Board Geometry/Outline")
		(27 "Margin" user)
		(31 "F.CrtYd" user "Package Geometry/Place Bound Top")
		(29 "B.CrtYd" user "Package Geometry/Place Bound Bottom")
		(35 "F.Fab" user "Ref Des/Assembly Top")
		(33 "B.Fab" user "Ref Des/Assembly Bottom")
	)
	(footprint ""
		(layer "F.Cu")
		(at 111.13897 -175.506634 -90)
		(property "Reference" "PC287"
			(at 0 0 270)
			(layer "F.SilkS")
			(hide yes)
			(effects
				(font
					(size 1.27 1.27)
				)
			)
		)
		(property "Value" ""
			(at 0 0 270)
			(layer "F.Fab")
			(effects
				(font
					(size 1.27 1.27)
				)
			)
		)
		(duplicate_pad_numbers_are_jumpers no)
		(fp_line
			(start -0.7874 0.4064)
			(end -0.7874 -0.4064)
			(stroke
				(width 0.1524)
				(type default)
			)
			(layer "F.SilkS")
		)
		(fp_line
			(start -0.362966 0.4064)
			(end -0.7874 0.4064)
			(stroke
				(width 0.1524)
				(type default)
			)
			(layer "F.SilkS")
		)
		(fp_line
			(start 0.7874 0.4064)
			(end 0.373634 0.4064)
			(stroke
				(width 0.1524)
				(type default)
			)
			(layer "F.SilkS")
		)
		(fp_line
			(start -0.7874 -0.4064)
			(end 0.7874 -0.4064)
			(stroke
				(width 0.1524)
				(type default)
			)
			(layer "F.SilkS")
		)
		(fp_line
			(start 0.7874 -0.4064)
			(end 0.7874 0.4064)
			(stroke
				(width 0.1524)
				(type default)
			)
			(layer "F.SilkS")
		)
		(fp_line
			(start -0.67945 0.3048)
			(end -0.67945 -0.305054)
			(stroke
				(width 0.1)
				(type default)
			)
			(layer "F.Fab")
		)
		(fp_line
			(start -0.12065 0.3048)
			(end -0.67945 0.3048)
			(stroke
				(width 0.1)
				(type default)
			)
			(layer "F.Fab")
		)
		(fp_line
			(start 0.120396 0.3048)
			(end 0.120396 0.2794)
			(stroke
				(width 0.1)
				(type default)
			)
			(layer "F.Fab")
		)
		(fp_line
			(start 0.67945 0.3048)
			(end 0.120396 0.3048)
			(stroke
				(width 0.1)
				(type default)
			)
			(layer "F.Fab")
		)
		(fp_line
			(start -0.12065 0.2794)
			(end -0.12065 0.3048)
			(stroke
				(width 0.1)
				(type default)
			)
			(layer "F.Fab")
		)
		(fp_line
			(start 0.120396 0.2794)
			(end -0.12065 0.2794)
			(stroke
				(width 0.1)
				(type default)
			)
			(layer "F.Fab")
		)
		(fp_line
			(start -0.12065 -0.2794)
			(end 0.12065 -0.2794)
			(stroke
				(width 0.1)
				(type default)
			)
			(layer "F.Fab")
		)
		(fp_line
			(start 0.12065 -0.2794)
			(end 0.12065 -0.3048)
			(stroke
				(width 0.1)
				(type default)
			)
			(layer "F.Fab")
		)
		(fp_line
			(start 0.12065 -0.3048)
			(end 0.67945 -0.3048)
			(stroke
				(width 0.1)
				(type default)
			)
			(layer "F.Fab")
		)
		(fp_line
			(start 0.67945 -0.3048)
			(end 0.67945 0.3048)
			(stroke
				(width 0.1)
				(type default)
			)
			(layer "F.Fab")
		)
		(fp_line
			(start -0.67945 -0.305054)
			(end -0.12065 -0.305054)
			(stroke
				(width 0.1)
				(type default)
			)
			(layer "F.Fab")
		)
		(fp_line
			(start -0.12065 -0.305054)
			(end -0.12065 -0.2794)
			(stroke
				(width 0.1)
				(type default)
			)
			(layer "F.Fab")
		)
		(pad "1" smd circle
			(at -0.40005 0 270)
			(size 0 0)
			(layers "F.Cu" "F.Mask" "F.Paste")
			(net "PVDDCR_CPU0_P1_VCC4")
		)
		(pad "2" smd circle
			(at 0.40005 0 270)
			(size 0 0)
			(layers "F.Cu" "F.Mask" "F.Paste")
			(net "GND")
		)
	)
	(footprint ""
		(layer "F.Cu")
		(at 88.344502 -375.49963 -90)
		(property "Reference" "C726"
			(at 0 0 270)
			(layer "F.SilkS")
			(hide yes)
			(effects
				(font
					(size 1.27 1.27)
				)
			)
		)
		(property "Value" ""
			(at 0 0 270)
			(layer "F.Fab")
			(effects
				(font
					(size 1.27 1.27)
				)
			)
		)
		(duplicate_pad_numbers_are_jumpers no)
		(fp_line
			(start -0.299974 0.150114)
			(end -0.299974 -0.150114)
			(stroke
				(width 0.1)
				(type default)
			)
			(layer "F.Fab")
		)
		(fp_line
			(start 0.299974 0.150114)
			(end -0.299974 0.150114)
			(stroke
				(width 0.1)
				(type default)
			)
			(layer "F.Fab")
		)
		(fp_line
			(start -0.299974 -0.150114)
			(end 0.299974 -0.150114)
			(stroke
				(width 0.1)
				(type default)
			)
			(layer "F.Fab")
		)
		(fp_line
			(start 0.299974 -0.150114)
			(end 0.299974 0.150114)
			(stroke
				(width 0.1)
				(type default)
			)
			(layer "F.Fab")
		)
		(pad "1" smd rect
			(at -0.2667 0 270)
			(size 0.3048 0.381)
			(layers "F.Cu" "F.Mask" "F.Paste")
			(net "P5E_CPU1_P1_TX_C_DN<7>")
		)
		(pad "2" smd rect
			(at 0.2667 0 270)
			(size 0.3048 0.381)
			(layers "F.Cu" "F.Mask" "F.Paste")
			(net "P5E_CPU1_P1_TX_DN<7>")
		)
	)
	(footprint ""
		(layer "F.Cu")
		(at 150.47722 -65.387474)
		(property "Reference" "Q62"
			(at -1.4224 -2.327148 0)
			(unlocked yes)
			(layer "F.SilkS")
			(effects
				(font
					(size 0.7874 0.5842)
					(thickness 0.1524)
				)
			)
		)
		(property "Value" ""
			(at 0 0 0)
			(layer "F.Fab")
			(effects
				(font
					(size 1.27 1.27)
				)
			)
		)
		(duplicate_pad_numbers_are_jumpers no)
		(fp_line
			(start -1.949958 -1.610106)
			(end 1.949958 -1.610106)
			(stroke
				(width 0.1524)
				(type default)
			)
			(layer "F.SilkS")
		)
		(fp_line
			(start -1.949958 1.610106)
			(end -1.949958 -1.610106)
			(stroke
				(width 0.1524)
				(type default)
			)
			(layer "F.SilkS")
		)
		(fp_line
			(start 1.949958 -1.560068)
			(end 1.949958 1.610106)
			(stroke
				(width 0.1524)
				(type default)
			)
			(layer "F.SilkS")
		)
		(fp_line
			(start 1.949958 1.610106)
			(end -1.949958 1.610106)
			(stroke
				(width 0.1524)
				(type default)
			)
			(layer "F.SilkS")
		)
		(fp_line
			(start -0.750062 -1.560068)
			(end 0.750062 -1.560068)
			(stroke
				(width 0.1)
				(type default)
			)
			(layer "F.Fab")
		)
		(fp_line
			(start -0.750062 1.560068)
			(end -0.750062 -1.560068)
			(stroke
				(width 0.1)
				(type default)
			)
			(layer "F.Fab")
		)
		(fp_line
			(start 0.750062 -1.560068)
			(end 0.750062 1.560068)
			(stroke
				(width 0.1)
				(type default)
			)
			(layer "F.Fab")
		)
		(fp_line
			(start 0.750062 1.560068)
			(end -0.750062 1.560068)
			(stroke
				(width 0.1)
				(type default)
			)
			(layer "F.Fab")
		)
		(pad "D" smd rect
			(at 1.100074 0 270)
			(size 1.016 1.4224)
			(layers "F.Cu" "F.Mask" "F.Paste")
			(net "JTAG_BMC_OE_N")
		)
		(pad "G" smd rect
			(at -1.100074 -0.94996 270)
			(size 1.016 1.4224)
			(layers "F.Cu" "F.Mask" "F.Paste")
			(net "JTAG_BMC_OE")
		)
		(pad "S" smd rect
			(at -1.100074 0.94996 270)
			(size 1.016 1.4224)
			(layers "F.Cu" "F.Mask" "F.Paste")
			(net "GND")
		)
	)
)
